;LEADER: 12 
;HEADER: 
;CODE  : ASCII 
;FILE  : 9127_F0T_Expander_BD_F_v02_0110_1240-bd-18-13.drl for backdrilling ... from layer BOTTOM to layer GND5
;DESIGN: 9127_F0T_Expander_BD_F_v02_0110_1240.brd
;MUST-NOT-CUT-LAYER = IN4,  MAX_DRILL_DEPTH = 40.45 MILS,  MFG_STUB_LENGTH = 0.00 MILS
;   BackdrillSize 1. = 15.700000 Tolerance = +0.000000/-0.000000 NON_PLATED MILS Quantity = 256
;   BackdrillSize 2. = 17.700000 Tolerance = +0.000000/-0.000000 NON_PLATED MILS Quantity = 384
;   BackdrillSize 3. = 19.900000 Tolerance = +0.000000/-0.000000 NON_PLATED MILS Quantity = 136
%
G90
X0201181Y1105117
X0189960Y1093897
X0231102Y1105117
X0178740Y1105117
X0204921Y1093897
X0201181Y1101376
X0186220Y1101376
X0178740Y1101376
X0174999Y1097637
X0227362Y1097637
X0219881Y1093897
X0193700Y1101376
X0182480Y1097637
X0216141Y1105117
X0212401Y1093897
X0208661Y1105117
X0182480Y1093897
X0197440Y1097637
X0186220Y1105117
X0223621Y1105117
X0189960Y1097637
X0212401Y1097637
X0174999Y1093897
X0223621Y1101376
X0219881Y1097637
X0227362Y1093897
X0231102Y1101376
X0197440Y1093897
X0208661Y1101376
X0193700Y1105117
X0216141Y1101376
X0204921Y1097637
X0302165Y1236023
X0320866Y1228543
X0313385Y1228543
X0317125Y1232283
X0305905Y1224803
X0324606Y1228543
X0305905Y1228543
X0309645Y1236023
X0313385Y1224803
X0320866Y1239763
X0298425Y1228543
X0290944Y1228543
X0294685Y1232283
X0298425Y1224803
X0290944Y1224803
X0294685Y1236023
X0317125Y1236023
X0324606Y1239763
X0309645Y1232283
X0302165Y1232283
X0294685Y1206102
X0302165Y1217322
X0298425Y1206102
X0294685Y1198621
X0302165Y1209842
X0305905Y1217322
X0302165Y1202362
X0294685Y1213582
X0305905Y1209842
X0305905Y1202362
X0298425Y1198621
X0298425Y1213582
X0650787Y1101376
X0643307Y1101376
X0635827Y1101376
X0658268Y1101376
X0639567Y1093897
X0658268Y1105117
X0647047Y1097637
X0665748Y1101376
X0643307Y1105117
X0662008Y1093897
X0632086Y1093897
X0635827Y1105117
X0639567Y1097637
X0654527Y1097637
X0647047Y1093897
X0665748Y1105117
X0654527Y1093897
X0650787Y1105117
X0632086Y1097637
X0662008Y1097637
X0632086Y1198621
X0624606Y1202362
X0624606Y1209842
X0620866Y1194881
X0628346Y1198621
X0632086Y1213582
X0628346Y1213582
X0632086Y1191141
X0624606Y1217322
X0620866Y1202362
X0624606Y1187401
X0624606Y1194881
X0632086Y1206102
X0620866Y1217322
X0620866Y1187401
X0620866Y1209842
X0628346Y1206102
X0628346Y1191141
X0613386Y1224803
X0609646Y1236023
X0624606Y1236023
X0624606Y1232283
X0602165Y1239763
X0605905Y1239763
X0617126Y1232283
X0613386Y1228543
X0617126Y1236023
X0602165Y1228543
X0609646Y1232283
X0620866Y1224803
X0620866Y1228543
X0605905Y1228543
X0680708Y1101376
X0673228Y1101376
X0680708Y1105117
X0676968Y1097637
X0684449Y1097637
X0669488Y1097637
X0688189Y1101376
X0676968Y1093897
X0669488Y1093897
X0684449Y1093897
X0688189Y1105117
X0673228Y1105117
X1107873Y1101376
X1115354Y1105117
X1122834Y1101376
X1137794Y1101376
X1119094Y1093897
X1122834Y1105117
X1126574Y1097637
X1141535Y1097637
X1107873Y1105117
X1089172Y1093897
X1145275Y1101376
X1092913Y1101376
X1096653Y1093897
X1100393Y1101376
X1137794Y1105117
X1134054Y1097637
X1130314Y1101376
X1111613Y1097637
X1104133Y1093897
X1100393Y1105117
X1096653Y1097637
X1134054Y1093897
X1130314Y1105117
X1111613Y1093897
X1104133Y1097637
X1141535Y1093897
X1115354Y1101376
X1119094Y1097637
X1089172Y1097637
X1126574Y1093897
X1092913Y1105117
X1145275Y1105117
X1216338Y1209842
X1208858Y1213582
X1208858Y1206102
X1212598Y1213582
X1216338Y1217322
X1212598Y1206102
X1220078Y1209842
X1220078Y1202362
X1216338Y1202362
X1208858Y1198621
X1212598Y1198621
X1220078Y1217322
X1208858Y1236023
X1235039Y1239763
X1220078Y1228543
X1223818Y1232283
X1235039Y1228543
X1212598Y1224803
X1216338Y1232283
X1216338Y1236023
X1231298Y1236023
X1223818Y1236023
X1205117Y1224803
X1227558Y1224803
X1205117Y1228543
X1208858Y1232283
X1227558Y1228543
X1238779Y1228543
X1212598Y1228543
X1220078Y1224803
X1238779Y1239763
X1231298Y1232283
X1527559Y1224803
X1538779Y1232283
X1523819Y1236023
X1520078Y1239763
X1531299Y1236023
X1520078Y1228543
X1523819Y1232283
X1516338Y1228543
X1535039Y1228543
X1516338Y1239763
X1531299Y1232283
X1527559Y1228543
X1538779Y1236023
X1535039Y1224803
X1538779Y1194881
X1535039Y1202362
X1538779Y1217322
X1538779Y1209842
X1538779Y1187401
X1546259Y1206102
X1535039Y1217322
X1546259Y1191141
X1546259Y1198621
X1535039Y1187401
X1535039Y1209842
X1546259Y1213582
X1542519Y1198621
X1542519Y1206102
X1535039Y1194881
X1538779Y1202362
X1542519Y1191141
X1542519Y1213582
X1546259Y1093897
X1546259Y1097637
X1564960Y1101376
X1553740Y1097637
X1568700Y1093897
X1553740Y1093897
X1550000Y1105117
X1550000Y1101376
X1561220Y1097637
X1568700Y1097637
X1557480Y1105117
X1561220Y1093897
X1564960Y1105117
X1557480Y1101376
X1579921Y1105117
X1572441Y1105117
X1572441Y1101376
X1602362Y1105117
X1587401Y1101376
X1591141Y1093897
X1598622Y1093897
X1579921Y1101376
X1587401Y1105117
X1576181Y1093897
X1598622Y1097637
X1583661Y1097637
X1594881Y1101376
X1583661Y1093897
X1576181Y1097637
X1591141Y1097637
X1594881Y1105117
X1602362Y1101376
M00
X0152952Y1408495
X0103992Y1396583
X0100592Y1360099
X0149552Y1396583
X0128472Y1396583
X0137312Y1372385
X0112832Y1372385
X0152952Y1396583
X0149552Y1408495
X0103992Y1408495
X0091752Y1384297
X0116232Y1384297
X0116232Y1372385
X0128472Y1348187
X0125072Y1396583
X0088352Y1384297
X0161792Y1372385
X0149552Y1348187
X0103992Y1348187
X0137312Y1384297
X0152952Y1360099
X0079512Y1348187
X0165192Y1384297
X0088352Y1372385
X0125072Y1360099
X0100592Y1348187
X0103992Y1360099
X0112832Y1384297
X0100592Y1408495
X0076112Y1348187
X0165192Y1372385
X0140712Y1384297
X0079512Y1360099
X0091752Y1372385
X0128472Y1360099
X0140712Y1372385
X0076112Y1360099
X0152952Y1348187
X0128472Y1408495
X0125072Y1408495
X0161792Y1384297
X0125072Y1348187
X0149552Y1360099
X0100592Y1396583
X0076005Y0128796
X0076005Y0125396
X0086407Y0135909
X0086407Y0132509
X0076005Y0111223
X0086407Y0121735
X0086407Y0118335
X0076005Y0114623
X0178367Y0114623
X0178367Y0111223
X0188769Y0121735
X0188769Y0118335
X0188769Y0132509
X0178367Y0125396
X0188769Y0135909
X0178367Y0128796
X0198512Y1408495
X0177432Y1360099
X0186272Y1372385
X0174032Y1408495
X0201912Y1360099
X0198512Y1360099
X0189672Y1372385
X0198512Y1396583
X0189672Y1384297
X0174032Y1396583
X0198512Y1348187
X0174032Y1360099
X0177432Y1408495
X0174032Y1348187
X0177432Y1396583
X0201912Y1348187
X0201912Y1396583
X0186272Y1384297
X0201912Y1408495
X0177432Y1348187
X0291131Y0132509
X0280729Y0128796
X0280729Y0125396
X0291131Y0135909
X0280729Y0114623
X0291131Y0118335
X0291131Y0121735
X0280729Y0111223
X0383091Y0114623
X0393493Y0121735
X0393493Y0118335
X0383091Y0111223
X0393493Y0132509
X0383091Y0128796
X0383091Y0125396
X0393493Y0135909
X0533092Y0125396
X0543494Y0132509
X0533092Y0128796
X0543494Y0135909
X0533092Y0111223
X0543494Y0118335
X0533092Y0114623
X0543494Y0121735
X0635454Y0111223
X0635454Y0114623
X0645856Y0121735
X0645856Y0118335
X0635454Y0125396
X0645856Y0135909
X0645856Y0132509
X0635454Y0128796
X0663008Y1348187
X0663008Y1396583
X0654168Y1372385
X0666408Y1348187
X0638528Y1396583
X0666408Y1396583
X0626288Y1396583
X0650768Y1372385
X0629688Y1396583
X0641928Y1396583
X0663008Y1408495
X0666408Y1408495
X0650768Y1384297
X0663008Y1360099
X0629688Y1408495
X0641928Y1408495
X0666408Y1360099
X0654168Y1384297
X0638528Y1408495
X0626288Y1408495
X0711968Y1360099
X0699728Y1384297
X0736448Y1408401
X0711968Y1408495
X0703128Y1384297
X0736448Y1348187
X0727608Y1372385
X0739848Y1360099
X0752088Y1384297
X0764328Y1348187
X0727608Y1384297
X0687488Y1348187
X0760928Y1348187
X0687488Y1396583
X0711968Y1396583
X0715368Y1360099
X0690888Y1396583
X0760928Y1360099
X0699728Y1372385
X0764328Y1360099
X0715368Y1396583
X0739848Y1408401
X0715368Y1408495
X0724208Y1384297
X0675248Y1372385
X0703128Y1372385
X0736448Y1360099
X0736448Y1396489
X0739848Y1348187
X0748688Y1384297
X0690888Y1348187
X0739848Y1396489
X0711968Y1348187
X0724208Y1372385
X0748688Y1372385
X0678648Y1372385
X0752088Y1372385
X0715368Y1348187
X0690888Y1360099
X0690888Y1408495
X0678648Y1384297
X0687488Y1408495
X0687488Y1360099
X0675248Y1384297
X0737816Y0125396
X0748218Y0132509
X0737816Y0128796
X0748218Y0135909
X0737816Y0111223
X0748218Y0121735
X0748218Y0118335
X0737816Y0114623
X0850580Y0121735
X0840178Y0111223
X0850580Y0118335
X0840178Y0114623
X0840178Y0125396
X0840178Y0128796
X0850580Y0135909
X0850580Y0132509
X1000580Y0118335
X0990178Y0111223
X0990178Y0114623
X1000580Y0121735
X1000580Y0132509
X0990178Y0125396
X1000580Y0135909
X0990178Y0128796
X1054713Y1348187
X1058113Y1348187
X1066953Y1372385
X1066953Y1384297
X1054713Y1360099
X1058113Y1360099
X1115913Y1384297
X1079193Y1408495
X1128153Y1360099
X1156033Y1360099
X1131553Y1408495
X1107073Y1360099
X1079193Y1360099
X1156033Y1408495
X1143793Y1384297
X1152633Y1360099
X1070353Y1384297
X1082593Y1408495
X1070353Y1372385
X1152633Y1396583
X1152633Y1348187
X1164873Y1372385
X1128153Y1348187
X1156033Y1348187
X1094833Y1372385
X1140393Y1372385
X1103673Y1348187
X1128153Y1396583
X1079193Y1348187
X1079193Y1396583
X1082593Y1396583
X1119313Y1372385
X1168273Y1372385
X1107073Y1348187
X1103673Y1396583
X1156033Y1396583
X1107073Y1396583
X1131553Y1396583
X1082593Y1348187
X1091433Y1372385
X1143793Y1372385
X1131553Y1348187
X1115913Y1372385
X1164873Y1384297
X1128153Y1408495
X1091433Y1384297
X1082593Y1360099
X1103673Y1408495
X1107073Y1408495
X1131553Y1360099
X1152633Y1408495
X1119313Y1384297
X1094833Y1384297
X1140393Y1384297
X1103673Y1360099
X1168273Y1384297
X1092540Y0125396
X1092540Y0128796
X1102942Y0132509
X1102942Y0135909
X1092540Y0114623
X1102942Y0121735
X1102942Y0118335
X1092540Y0111223
X1205304Y0121735
X1194902Y0111223
X1194902Y0114623
X1205304Y0118335
X1194902Y0125396
X1205304Y0132509
X1194902Y0128796
X1205304Y0135909
X1180513Y1408495
X1177113Y1408495
X1180513Y1348187
X1177113Y1348187
X1177113Y1396583
X1180513Y1396583
X1180513Y1360099
X1177113Y1360099
X1297264Y0125396
X1297264Y0128796
X1307666Y0135909
X1307666Y0132509
X1307666Y0121735
X1297264Y0111223
X1307666Y0118335
X1297264Y0114623
X1457667Y0121735
X1457667Y0118335
X1447265Y0114623
X1447265Y0111223
X1457667Y0132509
X1457667Y0135909
X1447265Y0128796
X1447265Y0125396
X1549627Y0125396
X1560029Y0135909
X1560029Y0132509
X1549627Y0128796
X1549627Y0114623
X1549627Y0111223
X1560029Y0118335
X1560029Y0121735
X1651989Y0111223
X1651989Y0114623
X1662391Y0121735
X1662391Y0118335
X1651989Y0128796
X1651989Y0125396
X1662391Y0132509
X1662391Y0135909
X1663758Y1408495
X1623638Y1384297
X1660358Y1360099
X1651518Y1384297
X1611398Y1360099
X1639278Y1408495
X1627038Y1384297
X1635878Y1360099
X1660358Y1408495
X1648118Y1384297
X1663758Y1360099
X1614798Y1360099
X1635878Y1408495
X1639278Y1360099
X1635878Y1348187
X1651518Y1372385
X1660358Y1396583
X1611398Y1348187
X1660358Y1348187
X1623638Y1372385
X1635878Y1396583
X1614798Y1348187
X1663758Y1396583
X1639278Y1396583
X1663758Y1348187
X1639278Y1348187
X1648118Y1372385
X1627038Y1372385
X1709318Y1408495
X1737198Y1360099
X1675998Y1384297
X1721558Y1384297
X1724958Y1384297
X1684838Y1408495
X1733798Y1408495
X1700478Y1384297
X1709318Y1360099
X1737198Y1408495
X1733798Y1360099
X1684838Y1360099
X1697078Y1384297
X1712718Y1360099
X1712718Y1408495
X1672598Y1384297
X1688238Y1408495
X1688238Y1360099
X1709318Y1396583
X1733798Y1396583
X1712718Y1348187
X1684838Y1348187
X1700478Y1372385
X1724958Y1372385
X1688238Y1396583
X1709318Y1348187
X1688238Y1348187
X1672598Y1372385
X1684838Y1396583
X1737198Y1348187
X1697078Y1372385
X1721558Y1372385
X1712718Y1396583
X1737198Y1396583
X1733798Y1348187
X1675998Y1372385
X1764753Y0132509
X1754351Y0125396
X1764753Y0135909
X1754351Y0128796
X1754351Y0114623
X1764753Y0118335
X1764753Y0121735
X1754351Y0111223
M00
X0118543Y1570434
X0109882Y1566103
X0118543Y1565315
X0109882Y1560985
X0135866Y1570434
X0127205Y1566103
X0135866Y1565315
X0127205Y1560985
X0153189Y1570434
X0144528Y1566103
X0153189Y1565315
X0144528Y1560985
X0161850Y1566103
X0161850Y1560985
X0118543Y1468071
X0109882Y1463741
X0118543Y1462953
X0109882Y1458622
X0135866Y1468071
X0127205Y1463741
X0135866Y1462953
X0127205Y1458622
X0153189Y1468071
X0144528Y1463741
X0153189Y1462953
X0144528Y1458622
X0161850Y1463741
X0161850Y1458622
X0170512Y1468071
X0170512Y1462953
X0170512Y1570434
X0170512Y1565315
X0187835Y1616496
X0187835Y1611378
X0187835Y1601142
X0187835Y1596024
X0361063Y1616496
X0361063Y1611378
X0361063Y1601142
X0361063Y1596024
X0638228Y1483426
X0629567Y1479095
X0638228Y1478308
X0629567Y1473977
X0655551Y1483426
X0646890Y1479095
X0655551Y1478308
X0646890Y1473977
X0664213Y1479095
X0664213Y1473977
X0638228Y1585788
X0629567Y1581457
X0638228Y1580670
X0629567Y1576339
X0655551Y1585788
X0646890Y1581457
X0655551Y1580670
X0646890Y1576339
X0664213Y1581457
X0664213Y1576339
X0672874Y1585788
X0672874Y1580670
X0690197Y1585788
X0681535Y1581457
X0690197Y1580670
X0681535Y1576339
X0672874Y1483426
X0672874Y1478308
X0690197Y1483426
X0681535Y1479095
X0690197Y1478308
X0681535Y1473977
X1140511Y1570434
X1131850Y1566103
X1140511Y1565315
X1131850Y1560985
X1157834Y1570434
X1149173Y1566103
X1157834Y1565315
X1149173Y1560985
X1166496Y1566103
X1166496Y1560985
X1140511Y1468071
X1131850Y1463741
X1140511Y1462953
X1131850Y1458622
X1157834Y1468071
X1149173Y1463741
X1157834Y1462953
X1149173Y1458622
X1166496Y1463741
X1166496Y1458622
X1175157Y1468071
X1175157Y1462953
X1192480Y1468071
X1183818Y1463741
X1192480Y1462953
X1183818Y1458622
X1175157Y1570434
X1175157Y1565315
X1192480Y1570434
X1183818Y1566103
X1192480Y1565315
X1183818Y1560985
X1660196Y1483426
X1651535Y1479095
X1660196Y1478308
X1651535Y1473977
X1668858Y1479095
X1668858Y1473977
X1660196Y1585788
X1651535Y1581457
X1660196Y1580670
X1651535Y1576339
X1668858Y1581457
X1668858Y1576339
X1677519Y1585788
X1677519Y1580670
X1694842Y1585788
X1686181Y1581457
X1694842Y1580670
X1686181Y1576339
X1712165Y1585788
X1703503Y1581457
X1712165Y1580670
X1703503Y1576339
X1677519Y1483426
X1677519Y1478308
X1694842Y1483426
X1686181Y1479095
X1694842Y1478308
X1686181Y1473977
X1712165Y1483426
X1703503Y1479095
X1712165Y1478308
X1703503Y1473977
M30
